(kicad_pcb
	(version 20260206)
	(generator "pcbnew")
	(generator_version "10.0")
	(general
		(thickness 1.6)
		(legacy_teardrops no)
	)
	(paper "A4")
	(title_block
		(title "04192023_DAF0TMB3IC0_F0TG_MB_C_brd_V02_OCP.brd")
		(comment 1 "Grand Teton / footprint 4612 of 8354 (J32), pads 1-113 of 291")
	)
	(layers
		(0 "F.Cu" signal "TOP")
		(4 "In1.Cu" signal "GND")
		(6 "In2.Cu" signal "IN1")
		(8 "In3.Cu" signal "GND1")
		(10 "In4.Cu" signal "IN2")
		(12 "In5.Cu" signal "GND2")
		(14 "In6.Cu" signal "IN3")
		(16 "In7.Cu" signal "GND3")
		(18 "In8.Cu" signal "VCC")
		(20 "In9.Cu" signal "VCC1")
		(22 "In10.Cu" signal "GND4")
		(24 "In11.Cu" signal "IN4")
		(26 "In12.Cu" signal "GND5")
		(28 "In13.Cu" signal "IN5")
		(30 "In14.Cu" signal "GND6")
		(32 "In15.Cu" signal "IN6")
		(34 "In16.Cu" signal "GND7")
		(2 "B.Cu" signal "BOTTOM")
		(9 "F.Adhes" user "F.Adhesive")
		(11 "B.Adhes" user "B.Adhesive")
		(13 "F.Paste" user "Package Geometry/Pastemask Top")
		(15 "B.Paste" user "Package Geometry/Pastemask Bottom")
		(5 "F.SilkS" user "Ref Des/Silkscreen Top")
		(7 "B.SilkS" user "Ref Des/Silkscreen Bottom")
		(1 "F.Mask" user "Board Geometry/Soldermask Top")
		(3 "B.Mask" user "Board Geometry/Soldermask Bottom")
		(17 "Dwgs.User" user "User.Drawings")
		(19 "Cmts.User" user "User.Comments")
		(21 "Eco1.User" user "User.Eco1")
		(23 "Eco2.User" user "User.Eco2")
		(25 "Edge.Cuts" user "Board Geometry/Outline")
		(27 "Margin" user)
		(31 "F.CrtYd" user "Package Geometry/Place Bound Top")
		(29 "B.CrtYd" user "Package Geometry/Place Bound Bottom")
		(35 "F.Fab" user "Ref Des/Assembly Top")
		(33 "B.Fab" user "Ref Des/Assembly Bottom")
	)
	(footprint ""
		(layer "F.Cu")
		(at 27.20213 -255.560322 180)
		(property "Reference" "J32"
			(at 1.80086 -81.974436 0)
			(unlocked yes)
			(layer "F.SilkS")
			(effects
				(font
					(size 0.7874 0.5842)
					(thickness 0.1524)
				)
			)
		)
		(property "Value" ""
			(at 0 0 180)
			(layer "F.Fab")
			(effects
				(font
					(size 1.27 1.27)
				)
			)
		)
		(duplicate_pad_numbers_are_jumpers no)
		(pad "1" smd rect
			(at -2.050034 -63.324994 90)
			(size 0.519938 1.4986)
			(layers "F.Cu" "F.Mask" "F.Paste")
			(net "P12V_MEM_CPU1")
		)
		(pad "2" smd rect
			(at -2.050034 -62.47511 90)
			(size 0.519938 1.4986)
			(layers "F.Cu" "F.Mask" "F.Paste")
			(net "Net_2312")
		)
		(pad "3" smd rect
			(at -2.050034 -61.624972 90)
			(size 0.519938 1.4986)
			(layers "F.Cu" "F.Mask" "F.Paste")
			(net "P3V3_AUX")
		)
		(pad "4" smd rect
			(at -2.050034 -60.775088 90)
			(size 0.519938 1.4986)
			(layers "F.Cu" "F.Mask" "F.Paste")
			(net "I3C_SPD_DDRE_CPU1_SCL")
		)
		(pad "5" smd rect
			(at -2.050034 -59.92495 90)
			(size 0.519938 1.4986)
			(layers "F.Cu" "F.Mask" "F.Paste")
			(net "I3C_SPD_DDRE_CPU1_SDA")
		)
		(pad "6" smd rect
			(at -2.050034 -59.075066 90)
			(size 0.519938 1.4986)
			(layers "F.Cu" "F.Mask" "F.Paste")
			(net "GND")
		)
		(pad "7" smd rect
			(at -2.050034 -58.224928 90)
			(size 0.519938 1.4986)
			(layers "F.Cu" "F.Mask" "F.Paste")
			(net "M_E_CPU1_SA_DQ<0>")
		)
		(pad "8" smd rect
			(at -2.050034 -57.375044 90)
			(size 0.519938 1.4986)
			(layers "F.Cu" "F.Mask" "F.Paste")
			(net "GND")
		)
		(pad "9" smd rect
			(at -2.050034 -56.524906 90)
			(size 0.519938 1.4986)
			(layers "F.Cu" "F.Mask" "F.Paste")
			(net "M_E_CPU1_SA_DQ<1>")
		)
		(pad "10" smd rect
			(at -2.050034 -55.675022 90)
			(size 0.519938 1.4986)
			(layers "F.Cu" "F.Mask" "F.Paste")
			(net "GND")
		)
		(pad "11" smd rect
			(at -2.050034 -54.824884 90)
			(size 0.519938 1.4986)
			(layers "F.Cu" "F.Mask" "F.Paste")
			(net "M_E_CPU1_SA_DQS_DP<0>")
		)
		(pad "12" smd rect
			(at -2.050034 -53.975 90)
			(size 0.519938 1.4986)
			(layers "F.Cu" "F.Mask" "F.Paste")
			(net "M_E_CPU1_SA_DQS_DN<0>")
		)
		(pad "13" smd rect
			(at -2.050034 -53.125116 90)
			(size 0.519938 1.4986)
			(layers "F.Cu" "F.Mask" "F.Paste")
			(net "GND")
		)
		(pad "14" smd rect
			(at -2.050034 -52.274978 90)
			(size 0.519938 1.4986)
			(layers "F.Cu" "F.Mask" "F.Paste")
			(net "M_E_CPU1_SA_DQ<4>")
		)
		(pad "15" smd rect
			(at -2.050034 -51.425094 90)
			(size 0.519938 1.4986)
			(layers "F.Cu" "F.Mask" "F.Paste")
			(net "GND")
		)
		(pad "16" smd rect
			(at -2.050034 -50.574956 90)
			(size 0.519938 1.4986)
			(layers "F.Cu" "F.Mask" "F.Paste")
			(net "M_E_CPU1_SA_DQ<5>")
		)
		(pad "17" smd rect
			(at -2.050034 -49.725072 90)
			(size 0.519938 1.4986)
			(layers "F.Cu" "F.Mask" "F.Paste")
			(net "GND")
		)
		(pad "18" smd rect
			(at -2.050034 -48.874934 90)
			(size 0.519938 1.4986)
			(layers "F.Cu" "F.Mask" "F.Paste")
			(net "M_E_CPU1_SA_DQ<8>")
		)
		(pad "19" smd rect
			(at -2.050034 -48.02505 90)
			(size 0.519938 1.4986)
			(layers "F.Cu" "F.Mask" "F.Paste")
			(net "GND")
		)
		(pad "20" smd rect
			(at -2.050034 -47.174912 90)
			(size 0.519938 1.4986)
			(layers "F.Cu" "F.Mask" "F.Paste")
			(net "M_E_CPU1_SA_DQ<9>")
		)
		(pad "21" smd rect
			(at -2.050034 -46.325028 90)
			(size 0.519938 1.4986)
			(layers "F.Cu" "F.Mask" "F.Paste")
			(net "GND")
		)
		(pad "22" smd rect
			(at -2.050034 -45.47489 90)
			(size 0.519938 1.4986)
			(layers "F.Cu" "F.Mask" "F.Paste")
			(net "M_E_CPU1_SA_DQS_DP<1>")
		)
		(pad "23" smd rect
			(at -2.050034 -44.625006 90)
			(size 0.519938 1.4986)
			(layers "F.Cu" "F.Mask" "F.Paste")
			(net "M_E_CPU1_SA_DQS_DN<1>")
		)
		(pad "24" smd rect
			(at -2.050034 -43.775122 90)
			(size 0.519938 1.4986)
			(layers "F.Cu" "F.Mask" "F.Paste")
			(net "GND")
		)
		(pad "25" smd rect
			(at -2.050034 -42.924984 90)
			(size 0.519938 1.4986)
			(layers "F.Cu" "F.Mask" "F.Paste")
			(net "M_E_CPU1_SA_DQ<12>")
		)
		(pad "26" smd rect
			(at -2.050034 -42.0751 90)
			(size 0.519938 1.4986)
			(layers "F.Cu" "F.Mask" "F.Paste")
			(net "GND")
		)
		(pad "27" smd rect
			(at -2.050034 -41.224962 90)
			(size 0.519938 1.4986)
			(layers "F.Cu" "F.Mask" "F.Paste")
			(net "M_E_CPU1_SA_DQ<13>")
		)
		(pad "28" smd rect
			(at -2.050034 -40.375078 90)
			(size 0.519938 1.4986)
			(layers "F.Cu" "F.Mask" "F.Paste")
			(net "GND")
		)
		(pad "29" smd rect
			(at -2.050034 -39.52494 90)
			(size 0.519938 1.4986)
			(layers "F.Cu" "F.Mask" "F.Paste")
			(net "M_E_CPU1_SA_DQ<16>")
		)
		(pad "30" smd rect
			(at -2.050034 -38.675056 90)
			(size 0.519938 1.4986)
			(layers "F.Cu" "F.Mask" "F.Paste")
			(net "GND")
		)
		(pad "31" smd rect
			(at -2.050034 -37.824918 90)
			(size 0.519938 1.4986)
			(layers "F.Cu" "F.Mask" "F.Paste")
			(net "M_E_CPU1_SA_DQ<17>")
		)
		(pad "32" smd rect
			(at -2.050034 -36.975034 90)
			(size 0.519938 1.4986)
			(layers "F.Cu" "F.Mask" "F.Paste")
			(net "GND")
		)
		(pad "33" smd rect
			(at -2.050034 -36.124896 90)
			(size 0.519938 1.4986)
			(layers "F.Cu" "F.Mask" "F.Paste")
			(net "M_E_CPU1_SA_DQS_DP<2>")
		)
		(pad "34" smd rect
			(at -2.050034 -35.275012 90)
			(size 0.519938 1.4986)
			(layers "F.Cu" "F.Mask" "F.Paste")
			(net "M_E_CPU1_SA_DQS_DN<2>")
		)
		(pad "35" smd rect
			(at -2.050034 -34.425128 90)
			(size 0.519938 1.4986)
			(layers "F.Cu" "F.Mask" "F.Paste")
			(net "GND")
		)
		(pad "36" smd rect
			(at -2.050034 -33.57499 90)
			(size 0.519938 1.4986)
			(layers "F.Cu" "F.Mask" "F.Paste")
			(net "M_E_CPU1_SA_DQ<20>")
		)
		(pad "37" smd rect
			(at -2.050034 -32.725106 90)
			(size 0.519938 1.4986)
			(layers "F.Cu" "F.Mask" "F.Paste")
			(net "GND")
		)
		(pad "38" smd rect
			(at -2.050034 -31.874968 90)
			(size 0.519938 1.4986)
			(layers "F.Cu" "F.Mask" "F.Paste")
			(net "M_E_CPU1_SA_DQ<21>")
		)
		(pad "39" smd rect
			(at -2.050034 -31.025084 90)
			(size 0.519938 1.4986)
			(layers "F.Cu" "F.Mask" "F.Paste")
			(net "GND")
		)
		(pad "40" smd rect
			(at -2.050034 -30.174946 90)
			(size 0.519938 1.4986)
			(layers "F.Cu" "F.Mask" "F.Paste")
			(net "M_E_CPU1_SA_DQ<24>")
		)
		(pad "41" smd rect
			(at -2.050034 -29.325062 90)
			(size 0.519938 1.4986)
			(layers "F.Cu" "F.Mask" "F.Paste")
			(net "GND")
		)
		(pad "42" smd rect
			(at -2.050034 -28.474924 90)
			(size 0.519938 1.4986)
			(layers "F.Cu" "F.Mask" "F.Paste")
			(net "M_E_CPU1_SA_DQ<25>")
		)
		(pad "43" smd rect
			(at -2.050034 -27.62504 90)
			(size 0.519938 1.4986)
			(layers "F.Cu" "F.Mask" "F.Paste")
			(net "GND")
		)
		(pad "44" smd rect
			(at -2.050034 -26.774902 90)
			(size 0.519938 1.4986)
			(layers "F.Cu" "F.Mask" "F.Paste")
			(net "M_E_CPU1_SA_DQS_DP<3>")
		)
		(pad "45" smd rect
			(at -2.050034 -25.925018 90)
			(size 0.519938 1.4986)
			(layers "F.Cu" "F.Mask" "F.Paste")
			(net "M_E_CPU1_SA_DQS_DN<3>")
		)
		(pad "46" smd rect
			(at -2.050034 -25.07488 90)
			(size 0.519938 1.4986)
			(layers "F.Cu" "F.Mask" "F.Paste")
			(net "GND")
		)
		(pad "47" smd rect
			(at -2.050034 -24.224996 90)
			(size 0.519938 1.4986)
			(layers "F.Cu" "F.Mask" "F.Paste")
			(net "M_E_CPU1_SA_DQ<28>")
		)
		(pad "48" smd rect
			(at -2.050034 -23.375112 90)
			(size 0.519938 1.4986)
			(layers "F.Cu" "F.Mask" "F.Paste")
			(net "GND")
		)
		(pad "49" smd rect
			(at -2.050034 -22.524974 90)
			(size 0.519938 1.4986)
			(layers "F.Cu" "F.Mask" "F.Paste")
			(net "M_E_CPU1_SA_DQ<29>")
		)
		(pad "50" smd rect
			(at -2.050034 -21.67509 90)
			(size 0.519938 1.4986)
			(layers "F.Cu" "F.Mask" "F.Paste")
			(net "GND")
		)
		(pad "51" smd rect
			(at -2.050034 -20.824952 90)
			(size 0.519938 1.4986)
			(layers "F.Cu" "F.Mask" "F.Paste")
			(net "M_E_CPU1_SA_CB<0>")
		)
		(pad "52" smd rect
			(at -2.050034 -19.975068 90)
			(size 0.519938 1.4986)
			(layers "F.Cu" "F.Mask" "F.Paste")
			(net "GND")
		)
		(pad "53" smd rect
			(at -2.050034 -19.12493 90)
			(size 0.519938 1.4986)
			(layers "F.Cu" "F.Mask" "F.Paste")
			(net "M_E_CPU1_SA_CB<1>")
		)
		(pad "54" smd rect
			(at -2.050034 -18.275046 90)
			(size 0.519938 1.4986)
			(layers "F.Cu" "F.Mask" "F.Paste")
			(net "GND")
		)
		(pad "55" smd rect
			(at -2.050034 -17.424908 90)
			(size 0.519938 1.4986)
			(layers "F.Cu" "F.Mask" "F.Paste")
			(net "M_E_CPU1_SA_DQS_DP<4>")
		)
		(pad "56" smd rect
			(at -2.050034 -16.575024 90)
			(size 0.519938 1.4986)
			(layers "F.Cu" "F.Mask" "F.Paste")
			(net "M_E_CPU1_SA_DQS_DN<4>")
		)
		(pad "57" smd rect
			(at -2.050034 -15.724886 90)
			(size 0.519938 1.4986)
			(layers "F.Cu" "F.Mask" "F.Paste")
			(net "GND")
		)
		(pad "58" smd rect
			(at -2.050034 -14.875002 90)
			(size 0.519938 1.4986)
			(layers "F.Cu" "F.Mask" "F.Paste")
			(net "M_E_CPU1_SA_CB<4>")
		)
		(pad "59" smd rect
			(at -2.050034 -14.025118 90)
			(size 0.519938 1.4986)
			(layers "F.Cu" "F.Mask" "F.Paste")
			(net "GND")
		)
		(pad "60" smd rect
			(at -2.050034 -13.17498 90)
			(size 0.519938 1.4986)
			(layers "F.Cu" "F.Mask" "F.Paste")
			(net "M_E_CPU1_SA_CB<5>")
		)
		(pad "61" smd rect
			(at -2.050034 -12.325096 90)
			(size 0.519938 1.4986)
			(layers "F.Cu" "F.Mask" "F.Paste")
			(net "GND")
		)
		(pad "62" smd rect
			(at -2.050034 -11.474958 90)
			(size 0.519938 1.4986)
			(layers "F.Cu" "F.Mask" "F.Paste")
			(net "M_E_CPU1_ALERT_N")
		)
		(pad "63" smd rect
			(at -2.050034 -10.625074 90)
			(size 0.519938 1.4986)
			(layers "F.Cu" "F.Mask" "F.Paste")
			(net "GND")
		)
		(pad "64" smd rect
			(at -2.050034 -9.774936 90)
			(size 0.519938 1.4986)
			(layers "F.Cu" "F.Mask" "F.Paste")
			(net "M_E_CPU1_SA_CS_N<0>")
		)
		(pad "65" smd rect
			(at -2.050034 -8.925052 90)
			(size 0.519938 1.4986)
			(layers "F.Cu" "F.Mask" "F.Paste")
			(net "GND")
		)
		(pad "66" smd rect
			(at -2.050034 -8.074914 90)
			(size 0.519938 1.4986)
			(layers "F.Cu" "F.Mask" "F.Paste")
			(net "M_E_CPU1_SA_CA<0>")
		)
		(pad "67" smd rect
			(at -2.050034 -7.22503 90)
			(size 0.519938 1.4986)
			(layers "F.Cu" "F.Mask" "F.Paste")
			(net "GND")
		)
		(pad "68" smd rect
			(at -2.050034 -6.374892 90)
			(size 0.519938 1.4986)
			(layers "F.Cu" "F.Mask" "F.Paste")
			(net "M_E_CPU1_SA_CA<2>")
		)
		(pad "69" smd rect
			(at -2.050034 -5.525008 90)
			(size 0.519938 1.4986)
			(layers "F.Cu" "F.Mask" "F.Paste")
			(net "GND")
		)
		(pad "70" smd rect
			(at -2.050034 -4.675124 90)
			(size 0.519938 1.4986)
			(layers "F.Cu" "F.Mask" "F.Paste")
			(net "M_E_CPU1_SA_CA<4>")
		)
		(pad "71" smd rect
			(at -2.050034 -3.824986 90)
			(size 0.519938 1.4986)
			(layers "F.Cu" "F.Mask" "F.Paste")
			(net "GND")
		)
		(pad "72" smd rect
			(at -2.050034 -2.975102 90)
			(size 0.519938 1.4986)
			(layers "F.Cu" "F.Mask" "F.Paste")
			(net "M_E_CPU1_SA_CA<6>")
		)
		(pad "73" smd rect
			(at -2.050034 -2.124964 90)
			(size 0.519938 1.4986)
			(layers "F.Cu" "F.Mask" "F.Paste")
			(net "GND")
		)
		(pad "74" smd rect
			(at -2.050034 -1.27508 90)
			(size 0.519938 1.4986)
			(layers "F.Cu" "F.Mask" "F.Paste")
			(net "M_E_CPU1_SA_PAR")
		)
		(pad "75" smd rect
			(at -2.050034 -0.424942 90)
			(size 0.519938 1.4986)
			(layers "F.Cu" "F.Mask" "F.Paste")
			(net "GND")
		)
		(pad "76" smd rect
			(at -2.050034 5.525008 90)
			(size 0.519938 1.4986)
			(layers "F.Cu" "F.Mask" "F.Paste")
			(net "M_E_CPU1_SB_CA<0>")
		)
		(pad "77" smd rect
			(at -2.050034 6.374892 90)
			(size 0.519938 1.4986)
			(layers "F.Cu" "F.Mask" "F.Paste")
			(net "GND")
		)
		(pad "78" smd rect
			(at -2.050034 7.22503 90)
			(size 0.519938 1.4986)
			(layers "F.Cu" "F.Mask" "F.Paste")
			(net "M_E_CPU1_SB_CA<2>")
		)
		(pad "79" smd rect
			(at -2.050034 8.074914 90)
			(size 0.519938 1.4986)
			(layers "F.Cu" "F.Mask" "F.Paste")
			(net "GND")
		)
		(pad "80" smd rect
			(at -2.050034 8.925052 90)
			(size 0.519938 1.4986)
			(layers "F.Cu" "F.Mask" "F.Paste")
			(net "M_E_CPU1_SB_CA<4>")
		)
		(pad "81" smd rect
			(at -2.050034 9.774936 90)
			(size 0.519938 1.4986)
			(layers "F.Cu" "F.Mask" "F.Paste")
			(net "GND")
		)
		(pad "82" smd rect
			(at -2.050034 10.625074 90)
			(size 0.519938 1.4986)
			(layers "F.Cu" "F.Mask" "F.Paste")
			(net "M_E_CPU1_SB_CA<6>")
		)
		(pad "83" smd rect
			(at -2.050034 11.474958 90)
			(size 0.519938 1.4986)
			(layers "F.Cu" "F.Mask" "F.Paste")
			(net "GND")
		)
		(pad "84" smd rect
			(at -2.050034 12.325096 90)
			(size 0.519938 1.4986)
			(layers "F.Cu" "F.Mask" "F.Paste")
			(net "M_E_CPU1_SB_CS_N<0>")
		)
		(pad "85" smd rect
			(at -2.050034 13.17498 90)
			(size 0.519938 1.4986)
			(layers "F.Cu" "F.Mask" "F.Paste")
			(net "GND")
		)
		(pad "86" smd rect
			(at -2.050034 14.025118 90)
			(size 0.519938 1.4986)
			(layers "F.Cu" "F.Mask" "F.Paste")
			(net "M_E_CPU1_SA_RSP<0>")
		)
		(pad "87" smd rect
			(at -2.050034 14.875002 90)
			(size 0.519938 1.4986)
			(layers "F.Cu" "F.Mask" "F.Paste")
			(net "M_E_CPU1_SB_RSP<0>")
		)
		(pad "88" smd rect
			(at -2.050034 15.724886 90)
			(size 0.519938 1.4986)
			(layers "F.Cu" "F.Mask" "F.Paste")
			(net "GND")
		)
		(pad "89" smd rect
			(at -2.050034 16.575024 90)
			(size 0.519938 1.4986)
			(layers "F.Cu" "F.Mask" "F.Paste")
			(net "M_E_CPU1_SB_CB<4>")
		)
		(pad "90" smd rect
			(at -2.050034 17.424908 90)
			(size 0.519938 1.4986)
			(layers "F.Cu" "F.Mask" "F.Paste")
			(net "GND")
		)
		(pad "91" smd rect
			(at -2.050034 18.275046 90)
			(size 0.519938 1.4986)
			(layers "F.Cu" "F.Mask" "F.Paste")
			(net "M_E_CPU1_SB_CB<5>")
		)
		(pad "92" smd rect
			(at -2.050034 19.12493 90)
			(size 0.519938 1.4986)
			(layers "F.Cu" "F.Mask" "F.Paste")
			(net "GND")
		)
		(pad "93" smd rect
			(at -2.050034 19.975068 90)
			(size 0.519938 1.4986)
			(layers "F.Cu" "F.Mask" "F.Paste")
			(net "M_E_CPU1_SB_DQS_DP<9>")
		)
		(pad "94" smd rect
			(at -2.050034 20.824952 90)
			(size 0.519938 1.4986)
			(layers "F.Cu" "F.Mask" "F.Paste")
			(net "M_E_CPU1_SB_DQS_DN<9>")
		)
		(pad "95" smd rect
			(at -2.050034 21.67509 90)
			(size 0.519938 1.4986)
			(layers "F.Cu" "F.Mask" "F.Paste")
			(net "GND")
		)
		(pad "96" smd rect
			(at -2.050034 22.524974 90)
			(size 0.519938 1.4986)
			(layers "F.Cu" "F.Mask" "F.Paste")
			(net "M_E_CPU1_SB_CB<0>")
		)
		(pad "97" smd rect
			(at -2.050034 23.375112 90)
			(size 0.519938 1.4986)
			(layers "F.Cu" "F.Mask" "F.Paste")
			(net "GND")
		)
		(pad "98" smd rect
			(at -2.050034 24.224996 90)
			(size 0.519938 1.4986)
			(layers "F.Cu" "F.Mask" "F.Paste")
			(net "M_E_CPU1_SB_CB<1>")
		)
		(pad "99" smd rect
			(at -2.050034 25.07488 90)
			(size 0.519938 1.4986)
			(layers "F.Cu" "F.Mask" "F.Paste")
			(net "GND")
		)
		(pad "100" smd rect
			(at -2.050034 25.925018 90)
			(size 0.519938 1.4986)
			(layers "F.Cu" "F.Mask" "F.Paste")
			(net "M_E_CPU1_SB_DQ<0>")
		)
		(pad "101" smd rect
			(at -2.050034 26.774902 90)
			(size 0.519938 1.4986)
			(layers "F.Cu" "F.Mask" "F.Paste")
			(net "GND")
		)
		(pad "102" smd rect
			(at -2.050034 27.62504 90)
			(size 0.519938 1.4986)
			(layers "F.Cu" "F.Mask" "F.Paste")
			(net "M_E_CPU1_SB_DQ<1>")
		)
		(pad "103" smd rect
			(at -2.050034 28.474924 90)
			(size 0.519938 1.4986)
			(layers "F.Cu" "F.Mask" "F.Paste")
			(net "GND")
		)
		(pad "104" smd rect
			(at -2.050034 29.325062 90)
			(size 0.519938 1.4986)
			(layers "F.Cu" "F.Mask" "F.Paste")
			(net "M_E_CPU1_SB_DQS_DP<0>")
		)
		(pad "105" smd rect
			(at -2.050034 30.174946 90)
			(size 0.519938 1.4986)
			(layers "F.Cu" "F.Mask" "F.Paste")
			(net "M_E_CPU1_SB_DQS_DN<0>")
		)
		(pad "106" smd rect
			(at -2.050034 31.025084 90)
			(size 0.519938 1.4986)
			(layers "F.Cu" "F.Mask" "F.Paste")
			(net "GND")
		)
		(pad "107" smd rect
			(at -2.050034 31.874968 90)
			(size 0.519938 1.4986)
			(layers "F.Cu" "F.Mask" "F.Paste")
			(net "M_E_CPU1_SB_DQ<4>")
		)
		(pad "108" smd rect
			(at -2.050034 32.725106 90)
			(size 0.519938 1.4986)
			(layers "F.Cu" "F.Mask" "F.Paste")
			(net "GND")
		)
		(pad "109" smd rect
			(at -2.050034 33.57499 90)
			(size 0.519938 1.4986)
			(layers "F.Cu" "F.Mask" "F.Paste")
			(net "M_E_CPU1_SB_DQ<5>")
		)
		(pad "110" smd rect
			(at -2.050034 34.425128 90)
			(size 0.519938 1.4986)
			(layers "F.Cu" "F.Mask" "F.Paste")
			(net "GND")
		)
		(pad "111" smd rect
			(at -2.050034 35.275012 90)
			(size 0.519938 1.4986)
			(layers "F.Cu" "F.Mask" "F.Paste")
			(net "M_E_CPU1_SB_DQ<8>")
		)
		(pad "112" smd rect
			(at -2.050034 36.124896 90)
			(size 0.519938 1.4986)
			(layers "F.Cu" "F.Mask" "F.Paste")
			(net "GND")
		)
		(pad "113" smd rect
			(at -2.050034 36.975034 90)
			(size 0.519938 1.4986)
			(layers "F.Cu" "F.Mask" "F.Paste")
			(net "M_E_CPU1_SB_DQ<9>")
		)
	)
)
